(kicad_pcb
	(version 20260206)
	(generator "pcbnew")
	(generator_version "10.0")
	(general
		(thickness 1.6)
		(legacy_teardrops no)
	)
	(paper "A4")
	(title_block
		(title "04192023_DAF0TMB3IC0_F0TG_MB_C_brd_V02_OCP.brd")
		(comment 1 "Grand Teton / footprints 6603-6609 of 8354")
	)
	(layers
		(0 "F.Cu" signal "TOP")
		(4 "In1.Cu" signal "GND")
		(6 "In2.Cu" signal "IN1")
		(8 "In3.Cu" signal "GND1")
		(10 "In4.Cu" signal "IN2")
		(12 "In5.Cu" signal "GND2")
		(14 "In6.Cu" signal "IN3")
		(16 "In7.Cu" signal "GND3")
		(18 "In8.Cu" signal "VCC")
		(20 "In9.Cu" signal "VCC1")
		(22 "In10.Cu" signal "GND4")
		(24 "In11.Cu" signal "IN4")
		(26 "In12.Cu" signal "GND5")
		(28 "In13.Cu" signal "IN5")
		(30 "In14.Cu" signal "GND6")
		(32 "In15.Cu" signal "IN6")
		(34 "In16.Cu" signal "GND7")
		(2 "B.Cu" signal "BOTTOM")
		(9 "F.Adhes" user "F.Adhesive")
		(11 "B.Adhes" user "B.Adhesive")
		(13 "F.Paste" user "Package Geometry/Pastemask Top")
		(15 "B.Paste" user "Package Geometry/Pastemask Bottom")
		(5 "F.SilkS" user "Ref Des/Silkscreen Top")
		(7 "B.SilkS" user "Ref Des/Silkscreen Bottom")
		(1 "F.Mask" user "Board Geometry/Soldermask Top")
		(3 "B.Mask" user "Board Geometry/Soldermask Bottom")
		(17 "Dwgs.User" user "User.Drawings")
		(19 "Cmts.User" user "User.Comments")
		(21 "Eco1.User" user "User.Eco1")
		(23 "Eco2.User" user "User.Eco2")
		(25 "Edge.Cuts" user "Board Geometry/Outline")
		(27 "Margin" user)
		(31 "F.CrtYd" user "Package Geometry/Place Bound Top")
		(29 "B.CrtYd" user "Package Geometry/Place Bound Bottom")
		(35 "F.Fab" user "Ref Des/Assembly Top")
		(33 "B.Fab" user "Ref Des/Assembly Bottom")
	)
	(footprint ""
		(layer "B.Cu")
		(at 20.489418 -413.99587)
		(property "Reference" "R6800"
			(at 0 0 0)
			(layer "B.SilkS")
			(hide yes)
			(effects
				(font
					(size 1.27 1.27)
				)
				(justify mirror)
			)
		)
		(property "Value" ""
			(at 0 0 0)
			(layer "B.Fab")
			(effects
				(font
					(size 1.27 1.27)
				)
				(justify mirror)
			)
		)
		(duplicate_pad_numbers_are_jumpers no)
		(fp_line
			(start -0.7874 -0.4064)
			(end -0.7874 0.4064)
			(stroke
				(width 0.1524)
				(type default)
			)
			(layer "B.SilkS")
		)
		(fp_line
			(start -0.7874 0.4064)
			(end 0.7874 0.4064)
			(stroke
				(width 0.1524)
				(type default)
			)
			(layer "B.SilkS")
		)
		(fp_line
			(start 0.7874 -0.4064)
			(end -0.7874 -0.4064)
			(stroke
				(width 0.1524)
				(type default)
			)
			(layer "B.SilkS")
		)
		(fp_line
			(start 0.7874 0.4064)
			(end 0.7874 -0.4064)
			(stroke
				(width 0.1524)
				(type default)
			)
			(layer "B.SilkS")
		)
		(fp_line
			(start -0.67945 -0.3048)
			(end -0.67945 0.3048)
			(stroke
				(width 0.1)
				(type default)
			)
			(layer "B.Fab")
		)
		(fp_line
			(start -0.67945 0.3048)
			(end -0.120396 0.3048)
			(stroke
				(width 0.1)
				(type default)
			)
			(layer "B.Fab")
		)
		(fp_line
			(start -0.12065 -0.3048)
			(end -0.67945 -0.3048)
			(stroke
				(width 0.1)
				(type default)
			)
			(layer "B.Fab")
		)
		(fp_line
			(start -0.12065 -0.2794)
			(end -0.12065 -0.3048)
			(stroke
				(width 0.1)
				(type default)
			)
			(layer "B.Fab")
		)
		(fp_line
			(start -0.120396 0.2794)
			(end 0.12065 0.2794)
			(stroke
				(width 0.1)
				(type default)
			)
			(layer "B.Fab")
		)
		(fp_line
			(start -0.120396 0.3048)
			(end -0.120396 0.2794)
			(stroke
				(width 0.1)
				(type default)
			)
			(layer "B.Fab")
		)
		(fp_line
			(start 0.12065 -0.305054)
			(end 0.12065 -0.2794)
			(stroke
				(width 0.1)
				(type default)
			)
			(layer "B.Fab")
		)
		(fp_line
			(start 0.12065 -0.2794)
			(end -0.12065 -0.2794)
			(stroke
				(width 0.1)
				(type default)
			)
			(layer "B.Fab")
		)
		(fp_line
			(start 0.12065 0.2794)
			(end 0.12065 0.3048)
			(stroke
				(width 0.1)
				(type default)
			)
			(layer "B.Fab")
		)
		(fp_line
			(start 0.12065 0.3048)
			(end 0.67945 0.3048)
			(stroke
				(width 0.1)
				(type default)
			)
			(layer "B.Fab")
		)
		(fp_line
			(start 0.67945 -0.305054)
			(end 0.12065 -0.305054)
			(stroke
				(width 0.1)
				(type default)
			)
			(layer "B.Fab")
		)
		(fp_line
			(start 0.67945 0.3048)
			(end 0.67945 -0.305054)
			(stroke
				(width 0.1)
				(type default)
			)
			(layer "B.Fab")
		)
		(pad "1" smd circle
			(at 0.40005 0 180)
			(size 0 0)
			(layers "B.Cu" "B.Mask" "B.Paste")
			(net "GND")
		)
		(pad "2" smd circle
			(at -0.40005 0 180)
			(size 0 0)
			(layers "B.Cu" "B.Mask" "B.Paste")
			(net "P0V9_RETIMER_CPU1_EN1_R")
		)
	)
	(footprint ""
		(layer "B.Cu")
		(at 370.122958 -245.487952)
		(property "Reference" "C2192"
			(at 0 0 0)
			(layer "B.SilkS")
			(hide yes)
			(effects
				(font
					(size 1.27 1.27)
				)
				(justify mirror)
			)
		)
		(property "Value" ""
			(at 0 0 0)
			(layer "B.Fab")
			(effects
				(font
					(size 1.27 1.27)
				)
				(justify mirror)
			)
		)
		(duplicate_pad_numbers_are_jumpers no)
		(fp_line
			(start -0.7874 -0.4064)
			(end -0.7874 0.4064)
			(stroke
				(width 0.1524)
				(type default)
			)
			(layer "B.SilkS")
		)
		(fp_line
			(start -0.7874 0.4064)
			(end 0.7874 0.4064)
			(stroke
				(width 0.1524)
				(type default)
			)
			(layer "B.SilkS")
		)
		(fp_line
			(start 0.7874 -0.4064)
			(end -0.7874 -0.4064)
			(stroke
				(width 0.1524)
				(type default)
			)
			(layer "B.SilkS")
		)
		(fp_line
			(start 0.7874 0.4064)
			(end 0.7874 -0.4064)
			(stroke
				(width 0.1524)
				(type default)
			)
			(layer "B.SilkS")
		)
		(fp_line
			(start -0.67945 -0.3048)
			(end -0.67945 0.3048)
			(stroke
				(width 0.1)
				(type default)
			)
			(layer "B.Fab")
		)
		(fp_line
			(start -0.67945 0.3048)
			(end -0.120396 0.3048)
			(stroke
				(width 0.1)
				(type default)
			)
			(layer "B.Fab")
		)
		(fp_line
			(start -0.12065 -0.3048)
			(end -0.67945 -0.3048)
			(stroke
				(width 0.1)
				(type default)
			)
			(layer "B.Fab")
		)
		(fp_line
			(start -0.12065 -0.2794)
			(end -0.12065 -0.3048)
			(stroke
				(width 0.1)
				(type default)
			)
			(layer "B.Fab")
		)
		(fp_line
			(start -0.120396 0.2794)
			(end 0.12065 0.2794)
			(stroke
				(width 0.1)
				(type default)
			)
			(layer "B.Fab")
		)
		(fp_line
			(start -0.120396 0.3048)
			(end -0.120396 0.2794)
			(stroke
				(width 0.1)
				(type default)
			)
			(layer "B.Fab")
		)
		(fp_line
			(start 0.12065 -0.305054)
			(end 0.12065 -0.2794)
			(stroke
				(width 0.1)
				(type default)
			)
			(layer "B.Fab")
		)
		(fp_line
			(start 0.12065 -0.2794)
			(end -0.12065 -0.2794)
			(stroke
				(width 0.1)
				(type default)
			)
			(layer "B.Fab")
		)
		(fp_line
			(start 0.12065 0.2794)
			(end 0.12065 0.3048)
			(stroke
				(width 0.1)
				(type default)
			)
			(layer "B.Fab")
		)
		(fp_line
			(start 0.12065 0.3048)
			(end 0.67945 0.3048)
			(stroke
				(width 0.1)
				(type default)
			)
			(layer "B.Fab")
		)
		(fp_line
			(start 0.67945 -0.305054)
			(end 0.12065 -0.305054)
			(stroke
				(width 0.1)
				(type default)
			)
			(layer "B.Fab")
		)
		(fp_line
			(start 0.67945 0.3048)
			(end 0.67945 -0.305054)
			(stroke
				(width 0.1)
				(type default)
			)
			(layer "B.Fab")
		)
		(pad "1" smd circle
			(at 0.40005 0 180)
			(size 0 0)
			(layers "B.Cu" "B.Mask" "B.Paste")
			(net "PVDDCR_CPU0_P0")
		)
		(pad "2" smd circle
			(at -0.40005 0 180)
			(size 0 0)
			(layers "B.Cu" "B.Mask" "B.Paste")
			(net "GND")
		)
	)
	(footprint ""
		(layer "B.Cu")
		(at 101.384862 -181.633876 90)
		(property "Reference" "PR193"
			(at 0 0 90)
			(layer "B.SilkS")
			(hide yes)
			(effects
				(font
					(size 1.27 1.27)
				)
				(justify mirror)
			)
		)
		(property "Value" ""
			(at 0 0 90)
			(layer "B.Fab")
			(effects
				(font
					(size 1.27 1.27)
				)
				(justify mirror)
			)
		)
		(duplicate_pad_numbers_are_jumpers no)
		(fp_line
			(start 0.7874 -0.4064)
			(end -0.7874 -0.4064)
			(stroke
				(width 0.1524)
				(type default)
			)
			(layer "B.SilkS")
		)
		(fp_line
			(start -0.7874 -0.4064)
			(end -0.7874 0.4064)
			(stroke
				(width 0.1524)
				(type default)
			)
			(layer "B.SilkS")
		)
		(fp_line
			(start 0.7874 0.4064)
			(end 0.7874 -0.4064)
			(stroke
				(width 0.1524)
				(type default)
			)
			(layer "B.SilkS")
		)
		(fp_line
			(start -0.7874 0.4064)
			(end 0.7874 0.4064)
			(stroke
				(width 0.1524)
				(type default)
			)
			(layer "B.SilkS")
		)
		(fp_line
			(start 0.67945 -0.305054)
			(end 0.12065 -0.305054)
			(stroke
				(width 0.1)
				(type default)
			)
			(layer "B.Fab")
		)
		(fp_line
			(start 0.12065 -0.305054)
			(end 0.12065 -0.2794)
			(stroke
				(width 0.1)
				(type default)
			)
			(layer "B.Fab")
		)
		(fp_line
			(start -0.12065 -0.3048)
			(end -0.67945 -0.3048)
			(stroke
				(width 0.1)
				(type default)
			)
			(layer "B.Fab")
		)
		(fp_line
			(start -0.67945 -0.3048)
			(end -0.67945 0.3048)
			(stroke
				(width 0.1)
				(type default)
			)
			(layer "B.Fab")
		)
		(fp_line
			(start 0.12065 -0.2794)
			(end -0.12065 -0.2794)
			(stroke
				(width 0.1)
				(type default)
			)
			(layer "B.Fab")
		)
		(fp_line
			(start -0.12065 -0.2794)
			(end -0.12065 -0.3048)
			(stroke
				(width 0.1)
				(type default)
			)
			(layer "B.Fab")
		)
		(fp_line
			(start 0.12065 0.2794)
			(end 0.12065 0.3048)
			(stroke
				(width 0.1)
				(type default)
			)
			(layer "B.Fab")
		)
		(fp_line
			(start -0.120396 0.2794)
			(end 0.12065 0.2794)
			(stroke
				(width 0.1)
				(type default)
			)
			(layer "B.Fab")
		)
		(fp_line
			(start 0.67945 0.3048)
			(end 0.67945 -0.305054)
			(stroke
				(width 0.1)
				(type default)
			)
			(layer "B.Fab")
		)
		(fp_line
			(start 0.12065 0.3048)
			(end 0.67945 0.3048)
			(stroke
				(width 0.1)
				(type default)
			)
			(layer "B.Fab")
		)
		(fp_line
			(start -0.120396 0.3048)
			(end -0.120396 0.2794)
			(stroke
				(width 0.1)
				(type default)
			)
			(layer "B.Fab")
		)
		(fp_line
			(start -0.67945 0.3048)
			(end -0.120396 0.3048)
			(stroke
				(width 0.1)
				(type default)
			)
			(layer "B.Fab")
		)
		(pad "1" smd circle
			(at 0.40005 0 270)
			(size 0 0)
			(layers "B.Cu" "B.Mask" "B.Paste")
			(net "PVDDCR_CPU0_P1_PVCC")
		)
		(pad "2" smd circle
			(at -0.40005 0 270)
			(size 0 0)
			(layers "B.Cu" "B.Mask" "B.Paste")
			(net "PVDDCR_CPU0_P1_VCC3")
		)
	)
	(footprint ""
		(layer "B.Cu")
		(at 372.937278 -138.424158 180)
		(property "Reference" "R8310"
			(at 0 0 0)
			(layer "B.SilkS")
			(hide yes)
			(effects
				(font
					(size 1.27 1.27)
				)
				(justify mirror)
			)
		)
		(property "Value" ""
			(at 0 0 0)
			(layer "B.Fab")
			(effects
				(font
					(size 1.27 1.27)
				)
				(justify mirror)
			)
		)
		(duplicate_pad_numbers_are_jumpers no)
		(fp_line
			(start 0.7874 0.4064)
			(end 0.7874 -0.4064)
			(stroke
				(width 0.1524)
				(type default)
			)
			(layer "B.SilkS")
		)
		(fp_line
			(start 0.7874 -0.4064)
			(end -0.7874 -0.4064)
			(stroke
				(width 0.1524)
				(type default)
			)
			(layer "B.SilkS")
		)
		(fp_line
			(start -0.7874 0.4064)
			(end 0.7874 0.4064)
			(stroke
				(width 0.1524)
				(type default)
			)
			(layer "B.SilkS")
		)
		(fp_line
			(start -0.7874 -0.4064)
			(end -0.7874 0.4064)
			(stroke
				(width 0.1524)
				(type default)
			)
			(layer "B.SilkS")
		)
		(fp_line
			(start 0.67945 0.3048)
			(end 0.67945 -0.305054)
			(stroke
				(width 0.1)
				(type default)
			)
			(layer "B.Fab")
		)
		(fp_line
			(start 0.67945 -0.305054)
			(end 0.12065 -0.305054)
			(stroke
				(width 0.1)
				(type default)
			)
			(layer "B.Fab")
		)
		(fp_line
			(start 0.12065 0.3048)
			(end 0.67945 0.3048)
			(stroke
				(width 0.1)
				(type default)
			)
			(layer "B.Fab")
		)
		(fp_line
			(start 0.12065 0.2794)
			(end 0.12065 0.3048)
			(stroke
				(width 0.1)
				(type default)
			)
			(layer "B.Fab")
		)
		(fp_line
			(start 0.12065 -0.2794)
			(end -0.12065 -0.2794)
			(stroke
				(width 0.1)
				(type default)
			)
			(layer "B.Fab")
		)
		(fp_line
			(start 0.12065 -0.305054)
			(end 0.12065 -0.2794)
			(stroke
				(width 0.1)
				(type default)
			)
			(layer "B.Fab")
		)
		(fp_line
			(start -0.120396 0.3048)
			(end -0.120396 0.2794)
			(stroke
				(width 0.1)
				(type default)
			)
			(layer "B.Fab")
		)
		(fp_line
			(start -0.120396 0.2794)
			(end 0.12065 0.2794)
			(stroke
				(width 0.1)
				(type default)
			)
			(layer "B.Fab")
		)
		(fp_line
			(start -0.12065 -0.2794)
			(end -0.12065 -0.3048)
			(stroke
				(width 0.1)
				(type default)
			)
			(layer "B.Fab")
		)
		(fp_line
			(start -0.12065 -0.3048)
			(end -0.67945 -0.3048)
			(stroke
				(width 0.1)
				(type default)
			)
			(layer "B.Fab")
		)
		(fp_line
			(start -0.67945 0.3048)
			(end -0.120396 0.3048)
			(stroke
				(width 0.1)
				(type default)
			)
			(layer "B.Fab")
		)
		(fp_line
			(start -0.67945 -0.3048)
			(end -0.67945 0.3048)
			(stroke
				(width 0.1)
				(type default)
			)
			(layer "B.Fab")
		)
		(pad "1" smd circle
			(at 0.40005 0)
			(size 0 0)
			(layers "B.Cu" "B.Mask" "B.Paste")
			(net "PVDDCR_CPU0_P0_PMALERT")
		)
		(pad "2" smd circle
			(at -0.40005 0)
			(size 0 0)
			(layers "B.Cu" "B.Mask" "B.Paste")
			(net "PVDDCR_CPU0_P0_PMALERT_R")
		)
	)
	(footprint ""
		(layer "B.Cu")
		(at 457.148184 -65.768982 90)
		(property "Reference" "PC1600"
			(at 0 0 90)
			(layer "B.SilkS")
			(hide yes)
			(effects
				(font
					(size 1.27 1.27)
				)
				(justify mirror)
			)
		)
		(property "Value" ""
			(at 0 0 90)
			(layer "B.Fab")
			(effects
				(font
					(size 1.27 1.27)
				)
				(justify mirror)
			)
		)
		(duplicate_pad_numbers_are_jumpers no)
		(fp_line
			(start 1.524 -0.762)
			(end -1.524 -0.762)
			(stroke
				(width 0.1524)
				(type default)
			)
			(layer "B.SilkS")
		)
		(fp_line
			(start -1.524 -0.762)
			(end -1.524 0.762)
			(stroke
				(width 0.1524)
				(type default)
			)
			(layer "B.SilkS")
		)
		(fp_line
			(start 1.524 0.762)
			(end 1.524 -0.762)
			(stroke
				(width 0.1524)
				(type default)
			)
			(layer "B.SilkS")
		)
		(fp_line
			(start -1.524 0.762)
			(end 1.524 0.762)
			(stroke
				(width 0.1524)
				(type default)
			)
			(layer "B.SilkS")
		)
		(fp_line
			(start 1.1049 -0.724916)
			(end 1.1049 0.724916)
			(stroke
				(width 0.1)
				(type default)
			)
			(layer "B.Fab")
		)
		(fp_line
			(start -1.1049 -0.724916)
			(end 1.1049 -0.724916)
			(stroke
				(width 0.1)
				(type default)
			)
			(layer "B.Fab")
		)
		(fp_line
			(start 1.1049 0.724916)
			(end -1.1049 0.724916)
			(stroke
				(width 0.1)
				(type default)
			)
			(layer "B.Fab")
		)
		(fp_line
			(start -1.1049 0.724916)
			(end -1.1049 -0.724916)
			(stroke
				(width 0.1)
				(type default)
			)
			(layer "B.Fab")
		)
		(pad "1" smd rect
			(at 0.889 0 90)
			(size 1.016 1.27)
			(layers "B.Cu" "B.Mask" "B.Paste")
			(net "P3V3_AUX")
		)
		(pad "2" smd rect
			(at -0.889 0 90)
			(size 1.016 1.27)
			(layers "B.Cu" "B.Mask" "B.Paste")
			(net "GND")
		)
	)
	(footprint ""
		(layer "B.Cu")
		(at 22.096984 -389.526526 -90)
		(property "Reference" "PR6627"
			(at 0 0 90)
			(layer "B.SilkS")
			(hide yes)
			(effects
				(font
					(size 1.27 1.27)
				)
				(justify mirror)
			)
		)
		(property "Value" ""
			(at 0 0 90)
			(layer "B.Fab")
			(effects
				(font
					(size 1.27 1.27)
				)
				(justify mirror)
			)
		)
		(duplicate_pad_numbers_are_jumpers no)
		(fp_line
			(start -0.7874 0.4064)
			(end 0.7874 0.4064)
			(stroke
				(width 0.1524)
				(type default)
			)
			(layer "B.SilkS")
		)
		(fp_line
			(start 0.7874 0.4064)
			(end 0.7874 -0.4064)
			(stroke
				(width 0.1524)
				(type default)
			)
			(layer "B.SilkS")
		)
		(fp_line
			(start -0.7874 -0.4064)
			(end -0.7874 0.4064)
			(stroke
				(width 0.1524)
				(type default)
			)
			(layer "B.SilkS")
		)
		(fp_line
			(start 0.7874 -0.4064)
			(end -0.7874 -0.4064)
			(stroke
				(width 0.1524)
				(type default)
			)
			(layer "B.SilkS")
		)
		(fp_line
			(start -0.67945 0.3048)
			(end -0.120396 0.3048)
			(stroke
				(width 0.1)
				(type default)
			)
			(layer "B.Fab")
		)
		(fp_line
			(start -0.120396 0.3048)
			(end -0.120396 0.2794)
			(stroke
				(width 0.1)
				(type default)
			)
			(layer "B.Fab")
		)
		(fp_line
			(start 0.12065 0.3048)
			(end 0.67945 0.3048)
			(stroke
				(width 0.1)
				(type default)
			)
			(layer "B.Fab")
		)
		(fp_line
			(start 0.67945 0.3048)
			(end 0.67945 -0.305054)
			(stroke
				(width 0.1)
				(type default)
			)
			(layer "B.Fab")
		)
		(fp_line
			(start -0.120396 0.2794)
			(end 0.12065 0.2794)
			(stroke
				(width 0.1)
				(type default)
			)
			(layer "B.Fab")
		)
		(fp_line
			(start 0.12065 0.2794)
			(end 0.12065 0.3048)
			(stroke
				(width 0.1)
				(type default)
			)
			(layer "B.Fab")
		)
		(fp_line
			(start -0.12065 -0.2794)
			(end -0.12065 -0.3048)
			(stroke
				(width 0.1)
				(type default)
			)
			(layer "B.Fab")
		)
		(fp_line
			(start 0.12065 -0.2794)
			(end -0.12065 -0.2794)
			(stroke
				(width 0.1)
				(type default)
			)
			(layer "B.Fab")
		)
		(fp_line
			(start -0.67945 -0.3048)
			(end -0.67945 0.3048)
			(stroke
				(width 0.1)
				(type default)
			)
			(layer "B.Fab")
		)
		(fp_line
			(start -0.12065 -0.3048)
			(end -0.67945 -0.3048)
			(stroke
				(width 0.1)
				(type default)
			)
			(layer "B.Fab")
		)
		(fp_line
			(start 0.12065 -0.305054)
			(end 0.12065 -0.2794)
			(stroke
				(width 0.1)
				(type default)
			)
			(layer "B.Fab")
		)
		(fp_line
			(start 0.67945 -0.305054)
			(end 0.12065 -0.305054)
			(stroke
				(width 0.1)
				(type default)
			)
			(layer "B.Fab")
		)
		(pad "1" smd circle
			(at 0.40005 0 90)
			(size 0 0)
			(layers "B.Cu" "B.Mask" "B.Paste")
			(net "P0V9_RETIMER_CPU1_PVCC")
		)
		(pad "2" smd circle
			(at -0.40005 0 90)
			(size 0 0)
			(layers "B.Cu" "B.Mask" "B.Paste")
			(net "P0V9_RETIMER_CPU1_VCC2")
		)
	)
	(footprint ""
		(layer "B.Cu")
		(at 346.705936 -395.148562 90)
		(property "Reference" "C598"
			(at 0 0 90)
			(layer "B.SilkS")
			(hide yes)
			(effects
				(font
					(size 1.27 1.27)
				)
				(justify mirror)
			)
		)
		(property "Value" ""
			(at 0 0 90)
			(layer "B.Fab")
			(effects
				(font
					(size 1.27 1.27)
				)
				(justify mirror)
			)
		)
		(duplicate_pad_numbers_are_jumpers no)
		(fp_line
			(start 0.299974 -0.150114)
			(end -0.299974 -0.150114)
			(stroke
				(width 0.1)
				(type default)
			)
			(layer "B.Fab")
		)
		(fp_line
			(start -0.299974 -0.150114)
			(end -0.299974 0.150114)
			(stroke
				(width 0.1)
				(type default)
			)
			(layer "B.Fab")
		)
		(fp_line
			(start 0.299974 0.150114)
			(end 0.299974 -0.150114)
			(stroke
				(width 0.1)
				(type default)
			)
			(layer "B.Fab")
		)
		(fp_line
			(start -0.299974 0.150114)
			(end 0.299974 0.150114)
			(stroke
				(width 0.1)
				(type default)
			)
			(layer "B.Fab")
		)
		(pad "1" smd rect
			(at 0.2667 0 270)
			(size 0.3048 0.381)
			(layers "B.Cu" "B.Mask" "B.Paste")
			(net "P1V8_CPU0_RT1_1A_1D")
		)
		(pad "2" smd rect
			(at -0.2667 0 270)
			(size 0.3048 0.381)
			(layers "B.Cu" "B.Mask" "B.Paste")
			(net "GND")
		)
	)
)
